# T6G (Grand Teton) — schematic netlist excerpt (pin names and nets, part order shuffled) for the footprints in the layout excerpt that follows; sources: Cadence DE-HDL packaged netlist, KiCad conversion of 04192023_DAF0TMB3IC0_F0TG_MB_C_brd_V02_OCP.brd

PC125  Q_CAP  2.2UF 10V 10% X6S  pkg C0402  page 213 : A = PVDDCR_CPU0_P1_VCC6 ; B = GND

(kicad_pcb
	(version 20260206)
	(generator "pcbnew")
	(generator_version "10.0")
	(general
		(thickness 1.6)
		(legacy_teardrops no)
	)
	(paper "A4")
	(title_block
		(title "04192023_DAF0TMB3IC0_F0TG_MB_C_brd_V02_OCP.brd")
		(comment 1 "Grand Teton / footprints 389-389 of 8354")
	)
	(layers
		(0 "F.Cu" signal "TOP")
		(4 "In1.Cu" signal "GND")
		(6 "In2.Cu" signal "IN1")
		(8 "In3.Cu" signal "GND1")
		(10 "In4.Cu" signal "IN2")
		(12 "In5.Cu" signal "GND2")
		(14 "In6.Cu" signal "IN3")
		(16 "In7.Cu" signal "GND3")
		(18 "In8.Cu" signal "VCC")
		(20 "In9.Cu" signal "VCC1")
		(22 "In10.Cu" signal "GND4")
		(24 "In11.Cu" signal "IN4")
		(26 "In12.Cu" signal "GND5")
		(28 "In13.Cu" signal "IN5")
		(30 "In14.Cu" signal "GND6")
		(32 "In15.Cu" signal "IN6")
		(34 "In16.Cu" signal "GND7")
		(2 "B.Cu" signal "BOTTOM")
		(9 "F.Adhes" user "F.Adhesive")
		(11 "B.Adhes" user "B.Adhesive")
		(13 "F.Paste" user "Package Geometry/Pastemask Top")
		(15 "B.Paste" user "Package Geometry/Pastemask Bottom")
		(5 "F.SilkS" user "Ref Des/Silkscreen Top")
		(7 "B.SilkS" user "Ref Des/Silkscreen Bottom")
		(1 "F.Mask" user "Board Geometry/Soldermask Top")
		(3 "B.Mask" user "Board Geometry/Soldermask Bottom")
		(17 "Dwgs.User" user "User.Drawings")
		(19 "Cmts.User" user "User.Comments")
		(21 "Eco1.User" user "User.Eco1")
		(23 "Eco2.User" user "User.Eco2")
		(25 "Edge.Cuts" user "Board Geometry/Outline")
		(27 "Margin" user)
		(31 "F.CrtYd" user "Package Geometry/Place Bound Top")
		(29 "B.CrtYd" user "Package Geometry/Place Bound Bottom")
		(35 "F.Fab" user "Ref Des/Assembly Top")
		(33 "B.Fab" user "Ref Des/Assembly Bottom")
	)
	(footprint ""
		(layer "F.Cu")
		(at 69.33057 -166.26332 -90)
		(property "Reference" "PC125"
			(at 0 0 270)
			(layer "F.SilkS")
			(hide yes)
			(effects
				(font
					(size 1.27 1.27)
				)
			)
		)
		(property "Value" ""
			(at 0 0 270)
			(layer "F.Fab")
			(effects
				(font
					(size 1.27 1.27)
				)
			)
		)
		(duplicate_pad_numbers_are_jumpers no)
		(fp_line
			(start -0.7874 0.4064)
			(end -0.7874 -0.4064)
			(stroke
				(width 0.1524)
				(type default)
			)
			(layer "F.SilkS")
		)
		(fp_line
			(start -0.36068 0.4064)
			(end -0.7874 0.4064)
			(stroke
				(width 0.1524)
				(type default)
			)
			(layer "F.SilkS")
		)
		(fp_line
			(start 0.7874 0.4064)
			(end 0.50292 0.4064)
			(stroke
				(width 0.1524)
				(type default)
			)
			(layer "F.SilkS")
		)
		(fp_line
			(start -0.7874 -0.4064)
			(end 0.7874 -0.4064)
			(stroke
				(width 0.1524)
				(type default)
			)
			(layer "F.SilkS")
		)
		(fp_line
			(start 0.7874 -0.4064)
			(end 0.7874 0.4064)
			(stroke
				(width 0.1524)
				(type default)
			)
			(layer "F.SilkS")
		)
		(fp_line
			(start -0.67945 0.3048)
			(end -0.67945 -0.305054)
			(stroke
				(width 0.1)
				(type default)
			)
			(layer "F.Fab")
		)
		(fp_line
			(start -0.12065 0.3048)
			(end -0.67945 0.3048)
			(stroke
				(width 0.1)
				(type default)
			)
			(layer "F.Fab")
		)
		(fp_line
			(start 0.120396 0.3048)
			(end 0.120396 0.2794)
			(stroke
				(width 0.1)
				(type default)
			)
			(layer "F.Fab")
		)
		(fp_line
			(start 0.67945 0.3048)
			(end 0.120396 0.3048)
			(stroke
				(width 0.1)
				(type default)
			)
			(layer "F.Fab")
		)
		(fp_line
			(start -0.12065 0.2794)
			(end -0.12065 0.3048)
			(stroke
				(width 0.1)
				(type default)
			)
			(layer "F.Fab")
		)
		(fp_line
			(start 0.120396 0.2794)
			(end -0.12065 0.2794)
			(stroke
				(width 0.1)
				(type default)
			)
			(layer "F.Fab")
		)
		(fp_line
			(start -0.12065 -0.2794)
			(end 0.12065 -0.2794)
			(stroke
				(width 0.1)
				(type default)
			)
			(layer "F.Fab")
		)
		(fp_line
			(start 0.12065 -0.2794)
			(end 0.12065 -0.3048)
			(stroke
				(width 0.1)
				(type default)
			)
			(layer "F.Fab")
		)
		(fp_line
			(start 0.12065 -0.3048)
			(end 0.67945 -0.3048)
			(stroke
				(width 0.1)
				(type default)
			)
			(layer "F.Fab")
		)
		(fp_line
			(start 0.67945 -0.3048)
			(end 0.67945 0.3048)
			(stroke
				(width 0.1)
				(type default)
			)
			(layer "F.Fab")
		)
		(fp_line
			(start -0.67945 -0.305054)
			(end -0.12065 -0.305054)
			(stroke
				(width 0.1)
				(type default)
			)
			(layer "F.Fab")
		)
		(fp_line
			(start -0.12065 -0.305054)
			(end -0.12065 -0.2794)
			(stroke
				(width 0.1)
				(type default)
			)
			(layer "F.Fab")
		)
		(pad "1" smd circle
			(at -0.40005 0 270)
			(size 0 0)
			(layers "F.Cu" "F.Mask" "F.Paste")
			(net "PVDDCR_CPU0_P1_VCC6")
		)
		(pad "2" smd circle
			(at 0.40005 0 270)
			(size 0 0)
			(layers "F.Cu" "F.Mask" "F.Paste")
			(net "GND")
		)
	)
)
